# S9S_MB_2U (Grand Teton) — schematic netlist excerpt (pin names and nets, part order shuffled) for the footprints in the layout excerpt that follows; sources: Cadence DE-HDL packaged netlist, KiCad conversion of 03242023_DA0F0TMBIJ0_F0T_Motherboard_J_brd_V01_OCP.brd

R912  Q_RES  4.75K 1% EMPTY  pkg 0402LF  page 208 : A = P3V3_AUX ; B = CLK_CK440_SMB_ADDR0
R2569  Q_RES  1K 1% CHIP  pkg 0402LF  page 292 : A = P3V3_AUX ; B = PVCCINFAON_CPU1_PIN_ALERT
PC261_P0_5  Q_CAP  22UF 16V 20% X6S  pkg C0805  page 269 : A = SW_P12V_PVCCIN_CPU0_FLT ; B = GND

(kicad_pcb
	(version 20260206)
	(generator "pcbnew")
	(generator_version "10.0")
	(general
		(thickness 1.6)
		(legacy_teardrops no)
	)
	(paper "A4")
	(title_block
		(title "03242023_DA0F0TMBIJ0_F0T_Motherboard_J_brd_V01_OCP.brd")
		(comment 1 "Grand Teton / footprints 5656-5658 of 6105")
	)
	(layers
		(0 "F.Cu" signal "TOP")
		(4 "In1.Cu" signal "GND")
		(6 "In2.Cu" signal "IN1")
		(8 "In3.Cu" signal "GND1")
		(10 "In4.Cu" signal "IN2")
		(12 "In5.Cu" signal "GND2")
		(14 "In6.Cu" signal "IN3")
		(16 "In7.Cu" signal "GND3")
		(18 "In8.Cu" signal "VCC")
		(20 "In9.Cu" signal "VCC1")
		(22 "In10.Cu" signal "GND4")
		(24 "In11.Cu" signal "IN4")
		(26 "In12.Cu" signal "GND5")
		(28 "In13.Cu" signal "IN5")
		(30 "In14.Cu" signal "GND6")
		(32 "In15.Cu" signal "IN6")
		(34 "In16.Cu" signal "GND7")
		(2 "B.Cu" signal "BOTTOM")
		(9 "F.Adhes" user "F.Adhesive")
		(11 "B.Adhes" user "B.Adhesive")
		(13 "F.Paste" user "Package Geometry/Pastemask Top")
		(15 "B.Paste" user "Package Geometry/Pastemask Bottom")
		(5 "F.SilkS" user "Ref Des/Silkscreen Top")
		(7 "B.SilkS" user "Ref Des/Silkscreen Bottom")
		(1 "F.Mask" user "Board Geometry/Soldermask Top")
		(3 "B.Mask" user "Board Geometry/Soldermask Bottom")
		(17 "Dwgs.User" user "User.Drawings")
		(19 "Cmts.User" user "User.Comments")
		(21 "Eco1.User" user "User.Eco1")
		(23 "Eco2.User" user "User.Eco2")
		(25 "Edge.Cuts" user "Board Geometry/Outline")
		(27 "Margin" user)
		(31 "F.CrtYd" user "Package Geometry/Place Bound Top")
		(29 "B.CrtYd" user "Package Geometry/Place Bound Bottom")
		(35 "F.Fab" user "Ref Des/Assembly Top")
		(33 "B.Fab" user "Ref Des/Assembly Bottom")
	)
	(footprint ""
		(layer "B.Cu")
		(at 245.818406 -98.092006 180)
		(property "Reference" "R912"
			(at 0 0 0)
			(layer "B.SilkS")
			(hide yes)
			(effects
				(font
					(size 1.27 1.27)
				)
				(justify mirror)
			)
		)
		(property "Value" ""
			(at 0 0 0)
			(layer "B.Fab")
			(effects
				(font
					(size 1.27 1.27)
				)
				(justify mirror)
			)
		)
		(duplicate_pad_numbers_are_jumpers no)
		(fp_line
			(start 0.7874 0.4064)
			(end 0.7874 -0.4064)
			(stroke
				(width 0.1524)
				(type default)
			)
			(layer "B.SilkS")
		)
		(fp_line
			(start 0.7874 -0.4064)
			(end -0.7874 -0.4064)
			(stroke
				(width 0.1524)
				(type default)
			)
			(layer "B.SilkS")
		)
		(fp_line
			(start -0.7874 0.4064)
			(end 0.7874 0.4064)
			(stroke
				(width 0.1524)
				(type default)
			)
			(layer "B.SilkS")
		)
		(fp_line
			(start -0.7874 -0.4064)
			(end -0.7874 0.4064)
			(stroke
				(width 0.1524)
				(type default)
			)
			(layer "B.SilkS")
		)
		(fp_line
			(start 0.67945 0.3048)
			(end 0.67945 -0.305054)
			(stroke
				(width 0.1)
				(type default)
			)
			(layer "B.Fab")
		)
		(fp_line
			(start 0.67945 -0.305054)
			(end 0.12065 -0.305054)
			(stroke
				(width 0.1)
				(type default)
			)
			(layer "B.Fab")
		)
		(fp_line
			(start 0.12065 0.3048)
			(end 0.67945 0.3048)
			(stroke
				(width 0.1)
				(type default)
			)
			(layer "B.Fab")
		)
		(fp_line
			(start 0.12065 0.2794)
			(end 0.12065 0.3048)
			(stroke
				(width 0.1)
				(type default)
			)
			(layer "B.Fab")
		)
		(fp_line
			(start 0.12065 -0.2794)
			(end -0.12065 -0.2794)
			(stroke
				(width 0.1)
				(type default)
			)
			(layer "B.Fab")
		)
		(fp_line
			(start 0.12065 -0.305054)
			(end 0.12065 -0.2794)
			(stroke
				(width 0.1)
				(type default)
			)
			(layer "B.Fab")
		)
		(fp_line
			(start -0.120396 0.3048)
			(end -0.120396 0.2794)
			(stroke
				(width 0.1)
				(type default)
			)
			(layer "B.Fab")
		)
		(fp_line
			(start -0.120396 0.2794)
			(end 0.12065 0.2794)
			(stroke
				(width 0.1)
				(type default)
			)
			(layer "B.Fab")
		)
		(fp_line
			(start -0.12065 -0.2794)
			(end -0.12065 -0.3048)
			(stroke
				(width 0.1)
				(type default)
			)
			(layer "B.Fab")
		)
		(fp_line
			(start -0.12065 -0.3048)
			(end -0.67945 -0.3048)
			(stroke
				(width 0.1)
				(type default)
			)
			(layer "B.Fab")
		)
		(fp_line
			(start -0.67945 0.3048)
			(end -0.120396 0.3048)
			(stroke
				(width 0.1)
				(type default)
			)
			(layer "B.Fab")
		)
		(fp_line
			(start -0.67945 -0.3048)
			(end -0.67945 0.3048)
			(stroke
				(width 0.1)
				(type default)
			)
			(layer "B.Fab")
		)
		(pad "1" smd circle
			(at 0.40005 0)
			(size 0 0)
			(layers "B.Cu" "B.Mask" "B.Paste")
			(net "P3V3_AUX")
		)
		(pad "2" smd circle
			(at -0.40005 0)
			(size 0 0)
			(layers "B.Cu" "B.Mask" "B.Paste")
			(net "CLK_CK440_SMB_ADDR0")
		)
	)
	(footprint ""
		(layer "B.Cu")
		(at 36.968938 -128.4097)
		(property "Reference" "R2569"
			(at 0 0 0)
			(layer "B.SilkS")
			(hide yes)
			(effects
				(font
					(size 1.27 1.27)
				)
				(justify mirror)
			)
		)
		(property "Value" ""
			(at 0 0 0)
			(layer "B.Fab")
			(effects
				(font
					(size 1.27 1.27)
				)
				(justify mirror)
			)
		)
		(duplicate_pad_numbers_are_jumpers no)
		(fp_line
			(start -0.7874 -0.4064)
			(end -0.7874 0.4064)
			(stroke
				(width 0.1524)
				(type default)
			)
			(layer "B.SilkS")
		)
		(fp_line
			(start -0.7874 0.4064)
			(end 0.7874 0.4064)
			(stroke
				(width 0.1524)
				(type default)
			)
			(layer "B.SilkS")
		)
		(fp_line
			(start 0.7874 -0.4064)
			(end -0.7874 -0.4064)
			(stroke
				(width 0.1524)
				(type default)
			)
			(layer "B.SilkS")
		)
		(fp_line
			(start 0.7874 0.4064)
			(end 0.7874 -0.4064)
			(stroke
				(width 0.1524)
				(type default)
			)
			(layer "B.SilkS")
		)
		(fp_line
			(start -0.67945 -0.3048)
			(end -0.67945 0.3048)
			(stroke
				(width 0.1)
				(type default)
			)
			(layer "B.Fab")
		)
		(fp_line
			(start -0.67945 0.3048)
			(end -0.120396 0.3048)
			(stroke
				(width 0.1)
				(type default)
			)
			(layer "B.Fab")
		)
		(fp_line
			(start -0.12065 -0.3048)
			(end -0.67945 -0.3048)
			(stroke
				(width 0.1)
				(type default)
			)
			(layer "B.Fab")
		)
		(fp_line
			(start -0.12065 -0.2794)
			(end -0.12065 -0.3048)
			(stroke
				(width 0.1)
				(type default)
			)
			(layer "B.Fab")
		)
		(fp_line
			(start -0.120396 0.2794)
			(end 0.12065 0.2794)
			(stroke
				(width 0.1)
				(type default)
			)
			(layer "B.Fab")
		)
		(fp_line
			(start -0.120396 0.3048)
			(end -0.120396 0.2794)
			(stroke
				(width 0.1)
				(type default)
			)
			(layer "B.Fab")
		)
		(fp_line
			(start 0.12065 -0.305054)
			(end 0.12065 -0.2794)
			(stroke
				(width 0.1)
				(type default)
			)
			(layer "B.Fab")
		)
		(fp_line
			(start 0.12065 -0.2794)
			(end -0.12065 -0.2794)
			(stroke
				(width 0.1)
				(type default)
			)
			(layer "B.Fab")
		)
		(fp_line
			(start 0.12065 0.2794)
			(end 0.12065 0.3048)
			(stroke
				(width 0.1)
				(type default)
			)
			(layer "B.Fab")
		)
		(fp_line
			(start 0.12065 0.3048)
			(end 0.67945 0.3048)
			(stroke
				(width 0.1)
				(type default)
			)
			(layer "B.Fab")
		)
		(fp_line
			(start 0.67945 -0.305054)
			(end 0.12065 -0.305054)
			(stroke
				(width 0.1)
				(type default)
			)
			(layer "B.Fab")
		)
		(fp_line
			(start 0.67945 0.3048)
			(end 0.67945 -0.305054)
			(stroke
				(width 0.1)
				(type default)
			)
			(layer "B.Fab")
		)
		(pad "1" smd circle
			(at 0.40005 0 180)
			(size 0 0)
			(layers "B.Cu" "B.Mask" "B.Paste")
			(net "P3V3_AUX")
		)
		(pad "2" smd circle
			(at -0.40005 0 180)
			(size 0 0)
			(layers "B.Cu" "B.Mask" "B.Paste")
			(net "PVCCINFAON_CPU1_PIN_ALERT")
		)
	)
	(footprint ""
		(layer "B.Cu")
		(at 380.808738 -337.161124 90)
		(property "Reference" "PC261_P0_5"
			(at 0 0 90)
			(layer "B.SilkS")
			(hide yes)
			(effects
				(font
					(size 1.27 1.27)
				)
				(justify mirror)
			)
		)
		(property "Value" ""
			(at 0 0 90)
			(layer "B.Fab")
			(effects
				(font
					(size 1.27 1.27)
				)
				(justify mirror)
			)
		)
		(duplicate_pad_numbers_are_jumpers no)
		(fp_line
			(start 1.524 -0.762)
			(end -1.524 -0.762)
			(stroke
				(width 0.1524)
				(type default)
			)
			(layer "B.SilkS")
		)
		(fp_line
			(start -1.524 -0.762)
			(end -1.524 0.762)
			(stroke
				(width 0.1524)
				(type default)
			)
			(layer "B.SilkS")
		)
		(fp_line
			(start 1.524 0.762)
			(end 1.524 -0.762)
			(stroke
				(width 0.1524)
				(type default)
			)
			(layer "B.SilkS")
		)
		(fp_line
			(start -1.524 0.762)
			(end 1.524 0.762)
			(stroke
				(width 0.1524)
				(type default)
			)
			(layer "B.SilkS")
		)
		(fp_line
			(start 1.1049 -0.724916)
			(end 1.1049 0.724916)
			(stroke
				(width 0.1)
				(type default)
			)
			(layer "B.Fab")
		)
		(fp_line
			(start -1.1049 -0.724916)
			(end 1.1049 -0.724916)
			(stroke
				(width 0.1)
				(type default)
			)
			(layer "B.Fab")
		)
		(fp_line
			(start 1.1049 0.724916)
			(end -1.1049 0.724916)
			(stroke
				(width 0.1)
				(type default)
			)
			(layer "B.Fab")
		)
		(fp_line
			(start -1.1049 0.724916)
			(end -1.1049 -0.724916)
			(stroke
				(width 0.1)
				(type default)
			)
			(layer "B.Fab")
		)
		(pad "1" smd rect
			(at 0.889 0 90)
			(size 1.016 1.27)
			(layers "B.Cu" "B.Mask" "B.Paste")
			(net "SW_P12V_PVCCIN_CPU0_FLT")
		)
		(pad "2" smd rect
			(at -0.889 0 90)
			(size 1.016 1.27)
			(layers "B.Cu" "B.Mask" "B.Paste")
			(net "GND")
		)
	)
)
